FILE_TYPE = CONNECTIVITY;
{Allegro Design Entry HDL 17.4-2019 S026 (4007227) 1/17/2022}
"PAGE_NUMBER" = 203;
0"NC";
END.
